# T6G (Grand Teton) — schematic netlist excerpt (pin names and nets, part order shuffled) for the footprints in the layout excerpt that follows; sources: Cadence DE-HDL packaged netlist, KiCad conversion of 04192023_DAF0TMB3IC0_F0TG_MB_C_brd_V02_OCP.brd

PC1599  Q_CAP  22UF 10V 20% X6S  pkg C0805  page 190 : A = P3V3_AUX ; B = GND
C1865  Q_CAP  0.1UF 25V 10% X7R  pkg 0402  page 111 : A = P3V3_AUX ; B = GND
R302  Q_RES  1K 1% CHIP  pkg 0402LF  page 97 : A = PWRGD_CHL_CPU0_DIMM ; B = PWRGD_CHGL_CPU0

(kicad_pcb
	(version 20260206)
	(generator "pcbnew")
	(generator_version "10.0")
	(general
		(thickness 1.6)
		(legacy_teardrops no)
	)
	(paper "A4")
	(title_block
		(title "04192023_DAF0TMB3IC0_F0TG_MB_C_brd_V02_OCP.brd")
		(comment 1 "Grand Teton / footprints 5536-5538 of 8354")
	)
	(layers
		(0 "F.Cu" signal "TOP")
		(4 "In1.Cu" signal "GND")
		(6 "In2.Cu" signal "IN1")
		(8 "In3.Cu" signal "GND1")
		(10 "In4.Cu" signal "IN2")
		(12 "In5.Cu" signal "GND2")
		(14 "In6.Cu" signal "IN3")
		(16 "In7.Cu" signal "GND3")
		(18 "In8.Cu" signal "VCC")
		(20 "In9.Cu" signal "VCC1")
		(22 "In10.Cu" signal "GND4")
		(24 "In11.Cu" signal "IN4")
		(26 "In12.Cu" signal "GND5")
		(28 "In13.Cu" signal "IN5")
		(30 "In14.Cu" signal "GND6")
		(32 "In15.Cu" signal "IN6")
		(34 "In16.Cu" signal "GND7")
		(2 "B.Cu" signal "BOTTOM")
		(9 "F.Adhes" user "F.Adhesive")
		(11 "B.Adhes" user "B.Adhesive")
		(13 "F.Paste" user "Package Geometry/Pastemask Top")
		(15 "B.Paste" user "Package Geometry/Pastemask Bottom")
		(5 "F.SilkS" user "Ref Des/Silkscreen Top")
		(7 "B.SilkS" user "Ref Des/Silkscreen Bottom")
		(1 "F.Mask" user "Board Geometry/Soldermask Top")
		(3 "B.Mask" user "Board Geometry/Soldermask Bottom")
		(17 "Dwgs.User" user "User.Drawings")
		(19 "Cmts.User" user "User.Comments")
		(21 "Eco1.User" user "User.Eco1")
		(23 "Eco2.User" user "User.Eco2")
		(25 "Edge.Cuts" user "Board Geometry/Outline")
		(27 "Margin" user)
		(31 "F.CrtYd" user "Package Geometry/Place Bound Top")
		(29 "B.CrtYd" user "Package Geometry/Place Bound Bottom")
		(35 "F.Fab" user "Ref Des/Assembly Top")
		(33 "B.Fab" user "Ref Des/Assembly Bottom")
	)
	(footprint ""
		(layer "B.Cu")
		(at 16.367252 -421.594026 -90)
		(property "Reference" "C1865"
			(at 0 0 90)
			(layer "B.SilkS")
			(hide yes)
			(effects
				(font
					(size 1.27 1.27)
				)
				(justify mirror)
			)
		)
		(property "Value" ""
			(at 0 0 90)
			(layer "B.Fab")
			(effects
				(font
					(size 1.27 1.27)
				)
				(justify mirror)
			)
		)
		(duplicate_pad_numbers_are_jumpers no)
		(fp_line
			(start -0.7874 0.4064)
			(end 0.7874 0.4064)
			(stroke
				(width 0.1524)
				(type default)
			)
			(layer "B.SilkS")
		)
		(fp_line
			(start 0.7874 0.4064)
			(end 0.7874 -0.4064)
			(stroke
				(width 0.1524)
				(type default)
			)
			(layer "B.SilkS")
		)
		(fp_line
			(start -0.7874 -0.4064)
			(end -0.7874 0.4064)
			(stroke
				(width 0.1524)
				(type default)
			)
			(layer "B.SilkS")
		)
		(fp_line
			(start 0.7874 -0.4064)
			(end -0.7874 -0.4064)
			(stroke
				(width 0.1524)
				(type default)
			)
			(layer "B.SilkS")
		)
		(fp_line
			(start -0.67945 0.3048)
			(end -0.120396 0.3048)
			(stroke
				(width 0.1)
				(type default)
			)
			(layer "B.Fab")
		)
		(fp_line
			(start -0.120396 0.3048)
			(end -0.120396 0.2794)
			(stroke
				(width 0.1)
				(type default)
			)
			(layer "B.Fab")
		)
		(fp_line
			(start 0.12065 0.3048)
			(end 0.67945 0.3048)
			(stroke
				(width 0.1)
				(type default)
			)
			(layer "B.Fab")
		)
		(fp_line
			(start 0.67945 0.3048)
			(end 0.67945 -0.305054)
			(stroke
				(width 0.1)
				(type default)
			)
			(layer "B.Fab")
		)
		(fp_line
			(start -0.120396 0.2794)
			(end 0.12065 0.2794)
			(stroke
				(width 0.1)
				(type default)
			)
			(layer "B.Fab")
		)
		(fp_line
			(start 0.12065 0.2794)
			(end 0.12065 0.3048)
			(stroke
				(width 0.1)
				(type default)
			)
			(layer "B.Fab")
		)
		(fp_line
			(start -0.12065 -0.2794)
			(end -0.12065 -0.3048)
			(stroke
				(width 0.1)
				(type default)
			)
			(layer "B.Fab")
		)
		(fp_line
			(start 0.12065 -0.2794)
			(end -0.12065 -0.2794)
			(stroke
				(width 0.1)
				(type default)
			)
			(layer "B.Fab")
		)
		(fp_line
			(start -0.67945 -0.3048)
			(end -0.67945 0.3048)
			(stroke
				(width 0.1)
				(type default)
			)
			(layer "B.Fab")
		)
		(fp_line
			(start -0.12065 -0.3048)
			(end -0.67945 -0.3048)
			(stroke
				(width 0.1)
				(type default)
			)
			(layer "B.Fab")
		)
		(fp_line
			(start 0.12065 -0.305054)
			(end 0.12065 -0.2794)
			(stroke
				(width 0.1)
				(type default)
			)
			(layer "B.Fab")
		)
		(fp_line
			(start 0.67945 -0.305054)
			(end 0.12065 -0.305054)
			(stroke
				(width 0.1)
				(type default)
			)
			(layer "B.Fab")
		)
		(pad "1" smd circle
			(at 0.40005 0 90)
			(size 0 0)
			(layers "B.Cu" "B.Mask" "B.Paste")
			(net "P3V3_AUX")
		)
		(pad "2" smd circle
			(at -0.40005 0 90)
			(size 0 0)
			(layers "B.Cu" "B.Mask" "B.Paste")
			(net "GND")
		)
	)
	(footprint ""
		(layer "B.Cu")
		(at 455.111104 -65.768982 90)
		(property "Reference" "PC1599"
			(at 0 0 90)
			(layer "B.SilkS")
			(hide yes)
			(effects
				(font
					(size 1.27 1.27)
				)
				(justify mirror)
			)
		)
		(property "Value" ""
			(at 0 0 90)
			(layer "B.Fab")
			(effects
				(font
					(size 1.27 1.27)
				)
				(justify mirror)
			)
		)
		(duplicate_pad_numbers_are_jumpers no)
		(fp_line
			(start 1.524 -0.762)
			(end -1.524 -0.762)
			(stroke
				(width 0.1524)
				(type default)
			)
			(layer "B.SilkS")
		)
		(fp_line
			(start -1.524 -0.762)
			(end -1.524 0.762)
			(stroke
				(width 0.1524)
				(type default)
			)
			(layer "B.SilkS")
		)
		(fp_line
			(start 1.524 0.762)
			(end 1.524 -0.762)
			(stroke
				(width 0.1524)
				(type default)
			)
			(layer "B.SilkS")
		)
		(fp_line
			(start -1.524 0.762)
			(end 1.524 0.762)
			(stroke
				(width 0.1524)
				(type default)
			)
			(layer "B.SilkS")
		)
		(fp_line
			(start 1.1049 -0.724916)
			(end 1.1049 0.724916)
			(stroke
				(width 0.1)
				(type default)
			)
			(layer "B.Fab")
		)
		(fp_line
			(start -1.1049 -0.724916)
			(end 1.1049 -0.724916)
			(stroke
				(width 0.1)
				(type default)
			)
			(layer "B.Fab")
		)
		(fp_line
			(start 1.1049 0.724916)
			(end -1.1049 0.724916)
			(stroke
				(width 0.1)
				(type default)
			)
			(layer "B.Fab")
		)
		(fp_line
			(start -1.1049 0.724916)
			(end -1.1049 -0.724916)
			(stroke
				(width 0.1)
				(type default)
			)
			(layer "B.Fab")
		)
		(pad "1" smd rect
			(at 0.889 0 90)
			(size 1.016 1.27)
			(layers "B.Cu" "B.Mask" "B.Paste")
			(net "P3V3_AUX")
		)
		(pad "2" smd rect
			(at -0.889 0 90)
			(size 1.016 1.27)
			(layers "B.Cu" "B.Mask" "B.Paste")
			(net "GND")
		)
	)
	(footprint ""
		(layer "B.Cu")
		(at 449.910454 -191.32931 180)
		(property "Reference" "R302"
			(at 0 0 0)
			(layer "B.SilkS")
			(hide yes)
			(effects
				(font
					(size 1.27 1.27)
				)
				(justify mirror)
			)
		)
		(property "Value" ""
			(at 0 0 0)
			(layer "B.Fab")
			(effects
				(font
					(size 1.27 1.27)
				)
				(justify mirror)
			)
		)
		(duplicate_pad_numbers_are_jumpers no)
		(fp_line
			(start 0.7874 0.4064)
			(end 0.7874 -0.4064)
			(stroke
				(width 0.1524)
				(type default)
			)
			(layer "B.SilkS")
		)
		(fp_line
			(start 0.7874 -0.4064)
			(end -0.7874 -0.4064)
			(stroke
				(width 0.1524)
				(type default)
			)
			(layer "B.SilkS")
		)
		(fp_line
			(start -0.7874 0.4064)
			(end 0.7874 0.4064)
			(stroke
				(width 0.1524)
				(type default)
			)
			(layer "B.SilkS")
		)
		(fp_line
			(start -0.7874 -0.4064)
			(end -0.7874 0.4064)
			(stroke
				(width 0.1524)
				(type default)
			)
			(layer "B.SilkS")
		)
		(fp_line
			(start 0.67945 0.3048)
			(end 0.67945 -0.305054)
			(stroke
				(width 0.1)
				(type default)
			)
			(layer "B.Fab")
		)
		(fp_line
			(start 0.67945 -0.305054)
			(end 0.12065 -0.305054)
			(stroke
				(width 0.1)
				(type default)
			)
			(layer "B.Fab")
		)
		(fp_line
			(start 0.12065 0.3048)
			(end 0.67945 0.3048)
			(stroke
				(width 0.1)
				(type default)
			)
			(layer "B.Fab")
		)
		(fp_line
			(start 0.12065 0.2794)
			(end 0.12065 0.3048)
			(stroke
				(width 0.1)
				(type default)
			)
			(layer "B.Fab")
		)
		(fp_line
			(start 0.12065 -0.2794)
			(end -0.12065 -0.2794)
			(stroke
				(width 0.1)
				(type default)
			)
			(layer "B.Fab")
		)
		(fp_line
			(start 0.12065 -0.305054)
			(end 0.12065 -0.2794)
			(stroke
				(width 0.1)
				(type default)
			)
			(layer "B.Fab")
		)
		(fp_line
			(start -0.120396 0.3048)
			(end -0.120396 0.2794)
			(stroke
				(width 0.1)
				(type default)
			)
			(layer "B.Fab")
		)
		(fp_line
			(start -0.120396 0.2794)
			(end 0.12065 0.2794)
			(stroke
				(width 0.1)
				(type default)
			)
			(layer "B.Fab")
		)
		(fp_line
			(start -0.12065 -0.2794)
			(end -0.12065 -0.3048)
			(stroke
				(width 0.1)
				(type default)
			)
			(layer "B.Fab")
		)
		(fp_line
			(start -0.12065 -0.3048)
			(end -0.67945 -0.3048)
			(stroke
				(width 0.1)
				(type default)
			)
			(layer "B.Fab")
		)
		(fp_line
			(start -0.67945 0.3048)
			(end -0.120396 0.3048)
			(stroke
				(width 0.1)
				(type default)
			)
			(layer "B.Fab")
		)
		(fp_line
			(start -0.67945 -0.3048)
			(end -0.67945 0.3048)
			(stroke
				(width 0.1)
				(type default)
			)
			(layer "B.Fab")
		)
		(pad "1" smd circle
			(at 0.40005 0)
			(size 0 0)
			(layers "B.Cu" "B.Mask" "B.Paste")
			(net "PWRGD_CHL_CPU0_DIMM")
		)
		(pad "2" smd circle
			(at -0.40005 0)
			(size 0 0)
			(layers "B.Cu" "B.Mask" "B.Paste")
			(net "PWRGD_CHGL_CPU0")
		)
	)
)
